(kicad_pcb
	(version 20260206)
	(generator "pcbnew")
	(generator_version "10.0")
	(general
		(thickness 1.6)
		(legacy_teardrops no)
	)
	(paper "A4")
	(title_block
		(title "04192023_DAF0TMB3IC0_F0TG_MB_C_brd_V02_OCP.brd")
		(comment 1 "Grand Teton / footprints 6770-6776 of 8354")
	)
	(layers
		(0 "F.Cu" signal "TOP")
		(4 "In1.Cu" signal "GND")
		(6 "In2.Cu" signal "IN1")
		(8 "In3.Cu" signal "GND1")
		(10 "In4.Cu" signal "IN2")
		(12 "In5.Cu" signal "GND2")
		(14 "In6.Cu" signal "IN3")
		(16 "In7.Cu" signal "GND3")
		(18 "In8.Cu" signal "VCC")
		(20 "In9.Cu" signal "VCC1")
		(22 "In10.Cu" signal "GND4")
		(24 "In11.Cu" signal "IN4")
		(26 "In12.Cu" signal "GND5")
		(28 "In13.Cu" signal "IN5")
		(30 "In14.Cu" signal "GND6")
		(32 "In15.Cu" signal "IN6")
		(34 "In16.Cu" signal "GND7")
		(2 "B.Cu" signal "BOTTOM")
		(9 "F.Adhes" user "F.Adhesive")
		(11 "B.Adhes" user "B.Adhesive")
		(13 "F.Paste" user "Package Geometry/Pastemask Top")
		(15 "B.Paste" user "Package Geometry/Pastemask Bottom")
		(5 "F.SilkS" user "Ref Des/Silkscreen Top")
		(7 "B.SilkS" user "Ref Des/Silkscreen Bottom")
		(1 "F.Mask" user "Board Geometry/Soldermask Top")
		(3 "B.Mask" user "Board Geometry/Soldermask Bottom")
		(17 "Dwgs.User" user "User.Drawings")
		(19 "Cmts.User" user "User.Comments")
		(21 "Eco1.User" user "User.Eco1")
		(23 "Eco2.User" user "User.Eco2")
		(25 "Edge.Cuts" user "Board Geometry/Outline")
		(27 "Margin" user)
		(31 "F.CrtYd" user "Package Geometry/Place Bound Top")
		(29 "B.CrtYd" user "Package Geometry/Place Bound Bottom")
		(35 "F.Fab" user "Ref Des/Assembly Top")
		(33 "B.Fab" user "Ref Des/Assembly Bottom")
	)
	(footprint ""
		(layer "B.Cu")
		(at 167.132 -118.328948 180)
		(property "Reference" "R890"
			(at 0 0 0)
			(layer "B.SilkS")
			(hide yes)
			(effects
				(font
					(size 1.27 1.27)
				)
				(justify mirror)
			)
		)
		(property "Value" ""
			(at 0 0 0)
			(layer "B.Fab")
			(effects
				(font
					(size 1.27 1.27)
				)
				(justify mirror)
			)
		)
		(duplicate_pad_numbers_are_jumpers no)
		(fp_line
			(start 0.7874 0.4064)
			(end 0.7874 -0.4064)
			(stroke
				(width 0.1524)
				(type default)
			)
			(layer "B.SilkS")
		)
		(fp_line
			(start 0.7874 -0.4064)
			(end -0.7874 -0.4064)
			(stroke
				(width 0.1524)
				(type default)
			)
			(layer "B.SilkS")
		)
		(fp_line
			(start -0.7874 0.4064)
			(end 0.7874 0.4064)
			(stroke
				(width 0.1524)
				(type default)
			)
			(layer "B.SilkS")
		)
		(fp_line
			(start -0.7874 -0.4064)
			(end -0.7874 0.4064)
			(stroke
				(width 0.1524)
				(type default)
			)
			(layer "B.SilkS")
		)
		(fp_line
			(start 0.67945 0.3048)
			(end 0.67945 -0.305054)
			(stroke
				(width 0.1)
				(type default)
			)
			(layer "B.Fab")
		)
		(fp_line
			(start 0.67945 -0.305054)
			(end 0.12065 -0.305054)
			(stroke
				(width 0.1)
				(type default)
			)
			(layer "B.Fab")
		)
		(fp_line
			(start 0.12065 0.3048)
			(end 0.67945 0.3048)
			(stroke
				(width 0.1)
				(type default)
			)
			(layer "B.Fab")
		)
		(fp_line
			(start 0.12065 0.2794)
			(end 0.12065 0.3048)
			(stroke
				(width 0.1)
				(type default)
			)
			(layer "B.Fab")
		)
		(fp_line
			(start 0.12065 -0.2794)
			(end -0.12065 -0.2794)
			(stroke
				(width 0.1)
				(type default)
			)
			(layer "B.Fab")
		)
		(fp_line
			(start 0.12065 -0.305054)
			(end 0.12065 -0.2794)
			(stroke
				(width 0.1)
				(type default)
			)
			(layer "B.Fab")
		)
		(fp_line
			(start -0.120396 0.3048)
			(end -0.120396 0.2794)
			(stroke
				(width 0.1)
				(type default)
			)
			(layer "B.Fab")
		)
		(fp_line
			(start -0.120396 0.2794)
			(end 0.12065 0.2794)
			(stroke
				(width 0.1)
				(type default)
			)
			(layer "B.Fab")
		)
		(fp_line
			(start -0.12065 -0.2794)
			(end -0.12065 -0.3048)
			(stroke
				(width 0.1)
				(type default)
			)
			(layer "B.Fab")
		)
		(fp_line
			(start -0.12065 -0.3048)
			(end -0.67945 -0.3048)
			(stroke
				(width 0.1)
				(type default)
			)
			(layer "B.Fab")
		)
		(fp_line
			(start -0.67945 0.3048)
			(end -0.120396 0.3048)
			(stroke
				(width 0.1)
				(type default)
			)
			(layer "B.Fab")
		)
		(fp_line
			(start -0.67945 -0.3048)
			(end -0.67945 0.3048)
			(stroke
				(width 0.1)
				(type default)
			)
			(layer "B.Fab")
		)
		(pad "1" smd circle
			(at 0.40005 0)
			(size 0 0)
			(layers "B.Cu" "B.Mask" "B.Paste")
			(net "P3V3_AUX")
		)
		(pad "2" smd circle
			(at -0.40005 0)
			(size 0 0)
			(layers "B.Cu" "B.Mask" "B.Paste")
			(net "SCM_SPARE_1")
		)
	)
	(footprint ""
		(layer "B.Cu")
		(at 326.667876 -66.708782 90)
		(property "Reference" "R3089"
			(at 0 0 90)
			(layer "B.SilkS")
			(hide yes)
			(effects
				(font
					(size 1.27 1.27)
				)
				(justify mirror)
			)
		)
		(property "Value" ""
			(at 0 0 90)
			(layer "B.Fab")
			(effects
				(font
					(size 1.27 1.27)
				)
				(justify mirror)
			)
		)
		(duplicate_pad_numbers_are_jumpers no)
		(fp_line
			(start 0.7874 -0.4064)
			(end -0.7874 -0.4064)
			(stroke
				(width 0.1524)
				(type default)
			)
			(layer "B.SilkS")
		)
		(fp_line
			(start -0.7874 -0.4064)
			(end -0.7874 0.4064)
			(stroke
				(width 0.1524)
				(type default)
			)
			(layer "B.SilkS")
		)
		(fp_line
			(start 0.7874 0.4064)
			(end 0.7874 -0.4064)
			(stroke
				(width 0.1524)
				(type default)
			)
			(layer "B.SilkS")
		)
		(fp_line
			(start -0.7874 0.4064)
			(end 0.7874 0.4064)
			(stroke
				(width 0.1524)
				(type default)
			)
			(layer "B.SilkS")
		)
		(fp_line
			(start 0.67945 -0.305054)
			(end 0.12065 -0.305054)
			(stroke
				(width 0.1)
				(type default)
			)
			(layer "B.Fab")
		)
		(fp_line
			(start 0.12065 -0.305054)
			(end 0.12065 -0.2794)
			(stroke
				(width 0.1)
				(type default)
			)
			(layer "B.Fab")
		)
		(fp_line
			(start -0.12065 -0.3048)
			(end -0.67945 -0.3048)
			(stroke
				(width 0.1)
				(type default)
			)
			(layer "B.Fab")
		)
		(fp_line
			(start -0.67945 -0.3048)
			(end -0.67945 0.3048)
			(stroke
				(width 0.1)
				(type default)
			)
			(layer "B.Fab")
		)
		(fp_line
			(start 0.12065 -0.2794)
			(end -0.12065 -0.2794)
			(stroke
				(width 0.1)
				(type default)
			)
			(layer "B.Fab")
		)
		(fp_line
			(start -0.12065 -0.2794)
			(end -0.12065 -0.3048)
			(stroke
				(width 0.1)
				(type default)
			)
			(layer "B.Fab")
		)
		(fp_line
			(start 0.12065 0.2794)
			(end 0.12065 0.3048)
			(stroke
				(width 0.1)
				(type default)
			)
			(layer "B.Fab")
		)
		(fp_line
			(start -0.120396 0.2794)
			(end 0.12065 0.2794)
			(stroke
				(width 0.1)
				(type default)
			)
			(layer "B.Fab")
		)
		(fp_line
			(start 0.67945 0.3048)
			(end 0.67945 -0.305054)
			(stroke
				(width 0.1)
				(type default)
			)
			(layer "B.Fab")
		)
		(fp_line
			(start 0.12065 0.3048)
			(end 0.67945 0.3048)
			(stroke
				(width 0.1)
				(type default)
			)
			(layer "B.Fab")
		)
		(fp_line
			(start -0.120396 0.3048)
			(end -0.120396 0.2794)
			(stroke
				(width 0.1)
				(type default)
			)
			(layer "B.Fab")
		)
		(fp_line
			(start -0.67945 0.3048)
			(end -0.120396 0.3048)
			(stroke
				(width 0.1)
				(type default)
			)
			(layer "B.Fab")
		)
		(pad "1" smd circle
			(at 0.40005 0 270)
			(size 0 0)
			(layers "B.Cu" "B.Mask" "B.Paste")
			(net "LED_PWRGD_PVDDCR_SOC_P0_R")
		)
		(pad "2" smd circle
			(at -0.40005 0 270)
			(size 0 0)
			(layers "B.Cu" "B.Mask" "B.Paste")
			(net "P3V3_AUX")
		)
	)
	(footprint ""
		(layer "B.Cu")
		(at 192.511426 -355.078284 -90)
		(property "Reference" "PC518_2"
			(at 0 0 90)
			(layer "B.SilkS")
			(hide yes)
			(effects
				(font
					(size 1.27 1.27)
				)
				(justify mirror)
			)
		)
		(property "Value" ""
			(at 0 0 90)
			(layer "B.Fab")
			(effects
				(font
					(size 1.27 1.27)
				)
				(justify mirror)
			)
		)
		(duplicate_pad_numbers_are_jumpers no)
		(fp_line
			(start -1.524 0.762)
			(end 1.524 0.762)
			(stroke
				(width 0.1524)
				(type default)
			)
			(layer "B.SilkS")
		)
		(fp_line
			(start 1.524 0.762)
			(end 1.524 -0.762)
			(stroke
				(width 0.1524)
				(type default)
			)
			(layer "B.SilkS")
		)
		(fp_line
			(start -1.524 -0.762)
			(end -1.524 0.762)
			(stroke
				(width 0.1524)
				(type default)
			)
			(layer "B.SilkS")
		)
		(fp_line
			(start 1.524 -0.762)
			(end -1.524 -0.762)
			(stroke
				(width 0.1524)
				(type default)
			)
			(layer "B.SilkS")
		)
		(fp_line
			(start -1.1049 0.724916)
			(end -1.1049 -0.724916)
			(stroke
				(width 0.1)
				(type default)
			)
			(layer "B.Fab")
		)
		(fp_line
			(start 1.1049 0.724916)
			(end -1.1049 0.724916)
			(stroke
				(width 0.1)
				(type default)
			)
			(layer "B.Fab")
		)
		(fp_line
			(start -1.1049 -0.724916)
			(end 1.1049 -0.724916)
			(stroke
				(width 0.1)
				(type default)
			)
			(layer "B.Fab")
		)
		(fp_line
			(start 1.1049 -0.724916)
			(end 1.1049 0.724916)
			(stroke
				(width 0.1)
				(type default)
			)
			(layer "B.Fab")
		)
		(pad "1" smd rect
			(at 0.889 0 270)
			(size 1.016 1.27)
			(layers "B.Cu" "B.Mask" "B.Paste")
			(net "SW_P12V_AUX_PVDD11_S3_P1_FLT")
		)
		(pad "2" smd rect
			(at -0.889 0 270)
			(size 1.016 1.27)
			(layers "B.Cu" "B.Mask" "B.Paste")
			(net "GND")
		)
	)
	(footprint ""
		(layer "B.Cu")
		(at 377.678442 -395.148562 90)
		(property "Reference" "C1001"
			(at 0 0 90)
			(layer "B.SilkS")
			(hide yes)
			(effects
				(font
					(size 1.27 1.27)
				)
				(justify mirror)
			)
		)
		(property "Value" ""
			(at 0 0 90)
			(layer "B.Fab")
			(effects
				(font
					(size 1.27 1.27)
				)
				(justify mirror)
			)
		)
		(duplicate_pad_numbers_are_jumpers no)
		(fp_line
			(start 0.299974 -0.150114)
			(end -0.299974 -0.150114)
			(stroke
				(width 0.1)
				(type default)
			)
			(layer "B.Fab")
		)
		(fp_line
			(start -0.299974 -0.150114)
			(end -0.299974 0.150114)
			(stroke
				(width 0.1)
				(type default)
			)
			(layer "B.Fab")
		)
		(fp_line
			(start 0.299974 0.150114)
			(end 0.299974 -0.150114)
			(stroke
				(width 0.1)
				(type default)
			)
			(layer "B.Fab")
		)
		(fp_line
			(start -0.299974 0.150114)
			(end 0.299974 0.150114)
			(stroke
				(width 0.1)
				(type default)
			)
			(layer "B.Fab")
		)
		(pad "1" smd rect
			(at 0.2667 0 270)
			(size 0.3048 0.381)
			(layers "B.Cu" "B.Mask" "B.Paste")
			(net "P1V8_CPU0_RT3_1A")
		)
		(pad "2" smd rect
			(at -0.2667 0 270)
			(size 0.3048 0.381)
			(layers "B.Cu" "B.Mask" "B.Paste")
			(net "GND")
		)
	)
	(footprint ""
		(layer "B.Cu")
		(at 197.269608 -120.737376 180)
		(property "Reference" "R4143"
			(at 0 0 0)
			(layer "B.SilkS")
			(hide yes)
			(effects
				(font
					(size 1.27 1.27)
				)
				(justify mirror)
			)
		)
		(property "Value" ""
			(at 0 0 0)
			(layer "B.Fab")
			(effects
				(font
					(size 1.27 1.27)
				)
				(justify mirror)
			)
		)
		(duplicate_pad_numbers_are_jumpers no)
		(fp_line
			(start 0.7874 0.4064)
			(end 0.7874 -0.4064)
			(stroke
				(width 0.1524)
				(type default)
			)
			(layer "B.SilkS")
		)
		(fp_line
			(start 0.7874 -0.4064)
			(end -0.7874 -0.4064)
			(stroke
				(width 0.1524)
				(type default)
			)
			(layer "B.SilkS")
		)
		(fp_line
			(start -0.7874 0.4064)
			(end 0.7874 0.4064)
			(stroke
				(width 0.1524)
				(type default)
			)
			(layer "B.SilkS")
		)
		(fp_line
			(start -0.7874 -0.4064)
			(end -0.7874 0.4064)
			(stroke
				(width 0.1524)
				(type default)
			)
			(layer "B.SilkS")
		)
		(fp_line
			(start 0.67945 0.3048)
			(end 0.67945 -0.305054)
			(stroke
				(width 0.1)
				(type default)
			)
			(layer "B.Fab")
		)
		(fp_line
			(start 0.67945 -0.305054)
			(end 0.12065 -0.305054)
			(stroke
				(width 0.1)
				(type default)
			)
			(layer "B.Fab")
		)
		(fp_line
			(start 0.12065 0.3048)
			(end 0.67945 0.3048)
			(stroke
				(width 0.1)
				(type default)
			)
			(layer "B.Fab")
		)
		(fp_line
			(start 0.12065 0.2794)
			(end 0.12065 0.3048)
			(stroke
				(width 0.1)
				(type default)
			)
			(layer "B.Fab")
		)
		(fp_line
			(start 0.12065 -0.2794)
			(end -0.12065 -0.2794)
			(stroke
				(width 0.1)
				(type default)
			)
			(layer "B.Fab")
		)
		(fp_line
			(start 0.12065 -0.305054)
			(end 0.12065 -0.2794)
			(stroke
				(width 0.1)
				(type default)
			)
			(layer "B.Fab")
		)
		(fp_line
			(start -0.120396 0.3048)
			(end -0.120396 0.2794)
			(stroke
				(width 0.1)
				(type default)
			)
			(layer "B.Fab")
		)
		(fp_line
			(start -0.120396 0.2794)
			(end 0.12065 0.2794)
			(stroke
				(width 0.1)
				(type default)
			)
			(layer "B.Fab")
		)
		(fp_line
			(start -0.12065 -0.2794)
			(end -0.12065 -0.3048)
			(stroke
				(width 0.1)
				(type default)
			)
			(layer "B.Fab")
		)
		(fp_line
			(start -0.12065 -0.3048)
			(end -0.67945 -0.3048)
			(stroke
				(width 0.1)
				(type default)
			)
			(layer "B.Fab")
		)
		(fp_line
			(start -0.67945 0.3048)
			(end -0.120396 0.3048)
			(stroke
				(width 0.1)
				(type default)
			)
			(layer "B.Fab")
		)
		(fp_line
			(start -0.67945 -0.3048)
			(end -0.67945 0.3048)
			(stroke
				(width 0.1)
				(type default)
			)
			(layer "B.Fab")
		)
		(pad "1" smd circle
			(at 0.40005 0)
			(size 0 0)
			(layers "B.Cu" "B.Mask" "B.Paste")
			(net "GPU_3V3IO_RSVD0_FFU_ISO_R")
		)
		(pad "2" smd circle
			(at -0.40005 0)
			(size 0 0)
			(layers "B.Cu" "B.Mask" "B.Paste")
			(net "GPU_3V3IO_RSVD0_FFU_ISO")
		)
	)
	(footprint ""
		(layer "B.Cu")
		(at 206.429356 -381.222504 180)
		(property "Reference" "PR2526"
			(at 0 0 0)
			(layer "B.SilkS")
			(hide yes)
			(effects
				(font
					(size 1.27 1.27)
				)
				(justify mirror)
			)
		)
		(property "Value" ""
			(at 0 0 0)
			(layer "B.Fab")
			(effects
				(font
					(size 1.27 1.27)
				)
				(justify mirror)
			)
		)
		(duplicate_pad_numbers_are_jumpers no)
		(fp_line
			(start 0.7874 0.4064)
			(end 0.7874 -0.4064)
			(stroke
				(width 0.1524)
				(type default)
			)
			(layer "B.SilkS")
		)
		(fp_line
			(start 0.7874 -0.4064)
			(end -0.7874 -0.4064)
			(stroke
				(width 0.1524)
				(type default)
			)
			(layer "B.SilkS")
		)
		(fp_line
			(start -0.7874 0.4064)
			(end 0.7874 0.4064)
			(stroke
				(width 0.1524)
				(type default)
			)
			(layer "B.SilkS")
		)
		(fp_line
			(start -0.7874 -0.4064)
			(end -0.7874 0.4064)
			(stroke
				(width 0.1524)
				(type default)
			)
			(layer "B.SilkS")
		)
		(fp_line
			(start 0.67945 0.3048)
			(end 0.67945 -0.305054)
			(stroke
				(width 0.1)
				(type default)
			)
			(layer "B.Fab")
		)
		(fp_line
			(start 0.67945 -0.305054)
			(end 0.12065 -0.305054)
			(stroke
				(width 0.1)
				(type default)
			)
			(layer "B.Fab")
		)
		(fp_line
			(start 0.12065 0.3048)
			(end 0.67945 0.3048)
			(stroke
				(width 0.1)
				(type default)
			)
			(layer "B.Fab")
		)
		(fp_line
			(start 0.12065 0.2794)
			(end 0.12065 0.3048)
			(stroke
				(width 0.1)
				(type default)
			)
			(layer "B.Fab")
		)
		(fp_line
			(start 0.12065 -0.2794)
			(end -0.12065 -0.2794)
			(stroke
				(width 0.1)
				(type default)
			)
			(layer "B.Fab")
		)
		(fp_line
			(start 0.12065 -0.305054)
			(end 0.12065 -0.2794)
			(stroke
				(width 0.1)
				(type default)
			)
			(layer "B.Fab")
		)
		(fp_line
			(start -0.120396 0.3048)
			(end -0.120396 0.2794)
			(stroke
				(width 0.1)
				(type default)
			)
			(layer "B.Fab")
		)
		(fp_line
			(start -0.120396 0.2794)
			(end 0.12065 0.2794)
			(stroke
				(width 0.1)
				(type default)
			)
			(layer "B.Fab")
		)
		(fp_line
			(start -0.12065 -0.2794)
			(end -0.12065 -0.3048)
			(stroke
				(width 0.1)
				(type default)
			)
			(layer "B.Fab")
		)
		(fp_line
			(start -0.12065 -0.3048)
			(end -0.67945 -0.3048)
			(stroke
				(width 0.1)
				(type default)
			)
			(layer "B.Fab")
		)
		(fp_line
			(start -0.67945 0.3048)
			(end -0.120396 0.3048)
			(stroke
				(width 0.1)
				(type default)
			)
			(layer "B.Fab")
		)
		(fp_line
			(start -0.67945 -0.3048)
			(end -0.67945 0.3048)
			(stroke
				(width 0.1)
				(type default)
			)
			(layer "B.Fab")
		)
		(pad "1" smd circle
			(at 0.40005 0)
			(size 0 0)
			(layers "B.Cu" "B.Mask" "B.Paste")
			(net "P12V_HSC_SENSE2_N")
		)
		(pad "2" smd circle
			(at -0.40005 0)
			(size 0 0)
			(layers "B.Cu" "B.Mask" "B.Paste")
			(net "P12V_HSC_SENSE2_R3_N")
		)
	)
	(footprint ""
		(layer "B.Cu")
		(at 189.35065 -13.60043 -90)
		(property "Reference" "R6001"
			(at 0 0 90)
			(layer "B.SilkS")
			(hide yes)
			(effects
				(font
					(size 1.27 1.27)
				)
				(justify mirror)
			)
		)
		(property "Value" ""
			(at 0 0 90)
			(layer "B.Fab")
			(effects
				(font
					(size 1.27 1.27)
				)
				(justify mirror)
			)
		)
		(duplicate_pad_numbers_are_jumpers no)
		(fp_line
			(start -0.7874 0.4064)
			(end 0.7874 0.4064)
			(stroke
				(width 0.1524)
				(type default)
			)
			(layer "B.SilkS")
		)
		(fp_line
			(start 0.7874 0.4064)
			(end 0.7874 -0.4064)
			(stroke
				(width 0.1524)
				(type default)
			)
			(layer "B.SilkS")
		)
		(fp_line
			(start -0.7874 -0.4064)
			(end -0.7874 0.4064)
			(stroke
				(width 0.1524)
				(type default)
			)
			(layer "B.SilkS")
		)
		(fp_line
			(start 0.7874 -0.4064)
			(end -0.7874 -0.4064)
			(stroke
				(width 0.1524)
				(type default)
			)
			(layer "B.SilkS")
		)
		(fp_line
			(start -0.67945 0.3048)
			(end -0.120396 0.3048)
			(stroke
				(width 0.1)
				(type default)
			)
			(layer "B.Fab")
		)
		(fp_line
			(start -0.120396 0.3048)
			(end -0.120396 0.2794)
			(stroke
				(width 0.1)
				(type default)
			)
			(layer "B.Fab")
		)
		(fp_line
			(start 0.12065 0.3048)
			(end 0.67945 0.3048)
			(stroke
				(width 0.1)
				(type default)
			)
			(layer "B.Fab")
		)
		(fp_line
			(start 0.67945 0.3048)
			(end 0.67945 -0.305054)
			(stroke
				(width 0.1)
				(type default)
			)
			(layer "B.Fab")
		)
		(fp_line
			(start -0.120396 0.2794)
			(end 0.12065 0.2794)
			(stroke
				(width 0.1)
				(type default)
			)
			(layer "B.Fab")
		)
		(fp_line
			(start 0.12065 0.2794)
			(end 0.12065 0.3048)
			(stroke
				(width 0.1)
				(type default)
			)
			(layer "B.Fab")
		)
		(fp_line
			(start -0.12065 -0.2794)
			(end -0.12065 -0.3048)
			(stroke
				(width 0.1)
				(type default)
			)
			(layer "B.Fab")
		)
		(fp_line
			(start 0.12065 -0.2794)
			(end -0.12065 -0.2794)
			(stroke
				(width 0.1)
				(type default)
			)
			(layer "B.Fab")
		)
		(fp_line
			(start -0.67945 -0.3048)
			(end -0.67945 0.3048)
			(stroke
				(width 0.1)
				(type default)
			)
			(layer "B.Fab")
		)
		(fp_line
			(start -0.12065 -0.3048)
			(end -0.67945 -0.3048)
			(stroke
				(width 0.1)
				(type default)
			)
			(layer "B.Fab")
		)
		(fp_line
			(start 0.12065 -0.305054)
			(end 0.12065 -0.2794)
			(stroke
				(width 0.1)
				(type default)
			)
			(layer "B.Fab")
		)
		(fp_line
			(start 0.67945 -0.305054)
			(end 0.12065 -0.305054)
			(stroke
				(width 0.1)
				(type default)
			)
			(layer "B.Fab")
		)
		(pad "1" smd circle
			(at 0.40005 0 90)
			(size 0 0)
			(layers "B.Cu" "B.Mask" "B.Paste")
			(net "I3C_SCM_0_SDA")
		)
		(pad "2" smd circle
			(at -0.40005 0 90)
			(size 0 0)
			(layers "B.Cu" "B.Mask" "B.Paste")
			(net "I3C_SCM_0_R_SDA")
		)
	)
)
